(kicad_pcb
	(version 20260206)
	(generator "pcbnew")
	(generator_version "10.0")
	(general
		(thickness 1.6)
		(legacy_teardrops no)
	)
	(paper "A4")
	(title_block
		(title "03242023_DA0F0TMBIJ0_F0T_Motherboard_J_brd_V01_OCP.brd")
		(comment 1 "Grand Teton / footprints 1967-1972 of 6105")
	)
	(layers
		(0 "F.Cu" signal "TOP")
		(4 "In1.Cu" signal "GND")
		(6 "In2.Cu" signal "IN1")
		(8 "In3.Cu" signal "GND1")
		(10 "In4.Cu" signal "IN2")
		(12 "In5.Cu" signal "GND2")
		(14 "In6.Cu" signal "IN3")
		(16 "In7.Cu" signal "GND3")
		(18 "In8.Cu" signal "VCC")
		(20 "In9.Cu" signal "VCC1")
		(22 "In10.Cu" signal "GND4")
		(24 "In11.Cu" signal "IN4")
		(26 "In12.Cu" signal "GND5")
		(28 "In13.Cu" signal "IN5")
		(30 "In14.Cu" signal "GND6")
		(32 "In15.Cu" signal "IN6")
		(34 "In16.Cu" signal "GND7")
		(2 "B.Cu" signal "BOTTOM")
		(9 "F.Adhes" user "F.Adhesive")
		(11 "B.Adhes" user "B.Adhesive")
		(13 "F.Paste" user "Package Geometry/Pastemask Top")
		(15 "B.Paste" user "Package Geometry/Pastemask Bottom")
		(5 "F.SilkS" user "Ref Des/Silkscreen Top")
		(7 "B.SilkS" user "Ref Des/Silkscreen Bottom")
		(1 "F.Mask" user "Board Geometry/Soldermask Top")
		(3 "B.Mask" user "Board Geometry/Soldermask Bottom")
		(17 "Dwgs.User" user "User.Drawings")
		(19 "Cmts.User" user "User.Comments")
		(21 "Eco1.User" user "User.Eco1")
		(23 "Eco2.User" user "User.Eco2")
		(25 "Edge.Cuts" user "Board Geometry/Outline")
		(27 "Margin" user)
		(31 "F.CrtYd" user "Package Geometry/Place Bound Top")
		(29 "B.CrtYd" user "Package Geometry/Place Bound Bottom")
		(35 "F.Fab" user "Ref Des/Assembly Top")
		(33 "B.Fab" user "Ref Des/Assembly Bottom")
	)
	(footprint ""
		(layer "F.Cu")
		(at 210.566 -97.6376)
		(property "Reference" "R2227"
			(at 0 0 0)
			(layer "F.SilkS")
			(hide yes)
			(effects
				(font
					(size 1.27 1.27)
				)
			)
		)
		(property "Value" ""
			(at 0 0 0)
			(layer "F.Fab")
			(effects
				(font
					(size 1.27 1.27)
				)
			)
		)
		(duplicate_pad_numbers_are_jumpers no)
		(fp_line
			(start -0.7874 -0.4064)
			(end 0.7874 -0.4064)
			(stroke
				(width 0.1524)
				(type default)
			)
			(layer "F.SilkS")
		)
		(fp_line
			(start -0.7874 0.4064)
			(end -0.7874 -0.4064)
			(stroke
				(width 0.1524)
				(type default)
			)
			(layer "F.SilkS")
		)
		(fp_line
			(start 0.7874 -0.4064)
			(end 0.7874 0.4064)
			(stroke
				(width 0.1524)
				(type default)
			)
			(layer "F.SilkS")
		)
		(fp_line
			(start 0.7874 0.4064)
			(end -0.7874 0.4064)
			(stroke
				(width 0.1524)
				(type default)
			)
			(layer "F.SilkS")
		)
		(fp_line
			(start -0.67945 -0.305054)
			(end -0.12065 -0.305054)
			(stroke
				(width 0.1)
				(type default)
			)
			(layer "F.Fab")
		)
		(fp_line
			(start -0.67945 0.3048)
			(end -0.67945 -0.305054)
			(stroke
				(width 0.1)
				(type default)
			)
			(layer "F.Fab")
		)
		(fp_line
			(start -0.12065 -0.305054)
			(end -0.12065 -0.2794)
			(stroke
				(width 0.1)
				(type default)
			)
			(layer "F.Fab")
		)
		(fp_line
			(start -0.12065 -0.2794)
			(end 0.12065 -0.2794)
			(stroke
				(width 0.1)
				(type default)
			)
			(layer "F.Fab")
		)
		(fp_line
			(start -0.12065 0.2794)
			(end -0.12065 0.3048)
			(stroke
				(width 0.1)
				(type default)
			)
			(layer "F.Fab")
		)
		(fp_line
			(start -0.12065 0.3048)
			(end -0.67945 0.3048)
			(stroke
				(width 0.1)
				(type default)
			)
			(layer "F.Fab")
		)
		(fp_line
			(start 0.120396 0.2794)
			(end -0.12065 0.2794)
			(stroke
				(width 0.1)
				(type default)
			)
			(layer "F.Fab")
		)
		(fp_line
			(start 0.120396 0.3048)
			(end 0.120396 0.2794)
			(stroke
				(width 0.1)
				(type default)
			)
			(layer "F.Fab")
		)
		(fp_line
			(start 0.12065 -0.3048)
			(end 0.67945 -0.3048)
			(stroke
				(width 0.1)
				(type default)
			)
			(layer "F.Fab")
		)
		(fp_line
			(start 0.12065 -0.2794)
			(end 0.12065 -0.3048)
			(stroke
				(width 0.1)
				(type default)
			)
			(layer "F.Fab")
		)
		(fp_line
			(start 0.67945 -0.3048)
			(end 0.67945 0.3048)
			(stroke
				(width 0.1)
				(type default)
			)
			(layer "F.Fab")
		)
		(fp_line
			(start 0.67945 0.3048)
			(end 0.120396 0.3048)
			(stroke
				(width 0.1)
				(type default)
			)
			(layer "F.Fab")
		)
		(pad "1" smd circle
			(at -0.40005 0)
			(size 0 0)
			(layers "F.Cu" "F.Mask" "F.Paste")
			(net "A_P12V_STBY_ADR_TRIGGER")
		)
		(pad "2" smd circle
			(at 0.40005 0)
			(size 0 0)
			(layers "F.Cu" "F.Mask" "F.Paste")
			(net "GND")
		)
	)
	(footprint ""
		(layer "F.Cu")
		(at 40.27678 -387.35127 -90)
		(property "Reference" "C2357"
			(at 0 0 270)
			(layer "F.SilkS")
			(hide yes)
			(effects
				(font
					(size 1.27 1.27)
				)
			)
		)
		(property "Value" ""
			(at 0 0 270)
			(layer "F.Fab")
			(effects
				(font
					(size 1.27 1.27)
				)
			)
		)
		(duplicate_pad_numbers_are_jumpers no)
		(fp_line
			(start -0.7874 0.4064)
			(end -0.7874 -0.4064)
			(stroke
				(width 0.1524)
				(type default)
			)
			(layer "F.SilkS")
		)
		(fp_line
			(start 0.7874 0.4064)
			(end -0.7874 0.4064)
			(stroke
				(width 0.1524)
				(type default)
			)
			(layer "F.SilkS")
		)
		(fp_line
			(start -0.7874 -0.4064)
			(end 0.7874 -0.4064)
			(stroke
				(width 0.1524)
				(type default)
			)
			(layer "F.SilkS")
		)
		(fp_line
			(start 0.7874 -0.4064)
			(end 0.7874 0.4064)
			(stroke
				(width 0.1524)
				(type default)
			)
			(layer "F.SilkS")
		)
		(fp_line
			(start -0.67945 0.3048)
			(end -0.67945 -0.305054)
			(stroke
				(width 0.1)
				(type default)
			)
			(layer "F.Fab")
		)
		(fp_line
			(start -0.12065 0.3048)
			(end -0.67945 0.3048)
			(stroke
				(width 0.1)
				(type default)
			)
			(layer "F.Fab")
		)
		(fp_line
			(start 0.120396 0.3048)
			(end 0.120396 0.2794)
			(stroke
				(width 0.1)
				(type default)
			)
			(layer "F.Fab")
		)
		(fp_line
			(start 0.67945 0.3048)
			(end 0.120396 0.3048)
			(stroke
				(width 0.1)
				(type default)
			)
			(layer "F.Fab")
		)
		(fp_line
			(start -0.12065 0.2794)
			(end -0.12065 0.3048)
			(stroke
				(width 0.1)
				(type default)
			)
			(layer "F.Fab")
		)
		(fp_line
			(start 0.120396 0.2794)
			(end -0.12065 0.2794)
			(stroke
				(width 0.1)
				(type default)
			)
			(layer "F.Fab")
		)
		(fp_line
			(start -0.12065 -0.2794)
			(end 0.12065 -0.2794)
			(stroke
				(width 0.1)
				(type default)
			)
			(layer "F.Fab")
		)
		(fp_line
			(start 0.12065 -0.2794)
			(end 0.12065 -0.3048)
			(stroke
				(width 0.1)
				(type default)
			)
			(layer "F.Fab")
		)
		(fp_line
			(start 0.12065 -0.3048)
			(end 0.67945 -0.3048)
			(stroke
				(width 0.1)
				(type default)
			)
			(layer "F.Fab")
		)
		(fp_line
			(start 0.67945 -0.3048)
			(end 0.67945 0.3048)
			(stroke
				(width 0.1)
				(type default)
			)
			(layer "F.Fab")
		)
		(fp_line
			(start -0.67945 -0.305054)
			(end -0.12065 -0.305054)
			(stroke
				(width 0.1)
				(type default)
			)
			(layer "F.Fab")
		)
		(fp_line
			(start -0.12065 -0.305054)
			(end -0.12065 -0.2794)
			(stroke
				(width 0.1)
				(type default)
			)
			(layer "F.Fab")
		)
		(pad "1" smd circle
			(at -0.40005 0 270)
			(size 0 0)
			(layers "F.Cu" "F.Mask" "F.Paste")
			(net "P2E_BUF2_VDD")
		)
		(pad "2" smd circle
			(at 0.40005 0 270)
			(size 0 0)
			(layers "F.Cu" "F.Mask" "F.Paste")
			(net "GND")
		)
	)
	(footprint ""
		(layer "F.Cu")
		(at 61.593476 -79.078836)
		(property "Reference" "D83"
			(at -33.022286 34.341308 90)
			(unlocked yes)
			(layer "F.SilkS")
			(effects
				(font
					(size 0.635 0.4064)
					(thickness 0.1524)
				)
				(justify left)
			)
		)
		(property "Value" ""
			(at 0 0 0)
			(layer "F.Fab")
			(effects
				(font
					(size 1.27 1.27)
				)
			)
		)
		(duplicate_pad_numbers_are_jumpers no)
		(fp_line
			(start -0.90678 0.4826)
			(end -0.90678 -0.4699)
			(stroke
				(width 0.1524)
				(type default)
			)
			(layer "F.SilkS")
		)
		(fp_line
			(start -0.89408 -0.4826)
			(end 0.90678 -0.4826)
			(stroke
				(width 0.1524)
				(type default)
			)
			(layer "F.SilkS")
		)
		(fp_line
			(start -0.79248 -0.4826)
			(end 1.03378 -0.4826)
			(stroke
				(width 0.1524)
				(type default)
			)
			(layer "F.SilkS")
		)
		(fp_line
			(start -0.64008 -0.4826)
			(end 1.16078 -0.4826)
			(stroke
				(width 0.1524)
				(type default)
			)
			(layer "F.SilkS")
		)
		(fp_line
			(start 0.90678 -0.4826)
			(end 0.90678 0.4826)
			(stroke
				(width 0.1524)
				(type default)
			)
			(layer "F.SilkS")
		)
		(fp_line
			(start 0.90678 0.4826)
			(end -0.90678 0.4826)
			(stroke
				(width 0.1524)
				(type default)
			)
			(layer "F.SilkS")
		)
		(fp_line
			(start 1.03378 -0.4826)
			(end 1.03378 0.4826)
			(stroke
				(width 0.1524)
				(type default)
			)
			(layer "F.SilkS")
		)
		(fp_line
			(start 1.03378 0.4826)
			(end -0.79248 0.4826)
			(stroke
				(width 0.1524)
				(type default)
			)
			(layer "F.SilkS")
		)
		(fp_line
			(start 1.16078 -0.4826)
			(end 1.16078 0.4826)
			(stroke
				(width 0.1524)
				(type default)
			)
			(layer "F.SilkS")
		)
		(fp_line
			(start 1.16078 0.4826)
			(end -0.64008 0.4826)
			(stroke
				(width 0.1524)
				(type default)
			)
			(layer "F.SilkS")
		)
		(fp_line
			(start -0.499872 -0.249936)
			(end 0.499872 -0.249936)
			(stroke
				(width 0.1)
				(type default)
			)
			(layer "F.Fab")
		)
		(fp_line
			(start -0.499872 0.249936)
			(end -0.499872 -0.249936)
			(stroke
				(width 0.1)
				(type default)
			)
			(layer "F.Fab")
		)
		(fp_line
			(start 0.499872 -0.249936)
			(end 0.499872 0.249936)
			(stroke
				(width 0.1)
				(type default)
			)
			(layer "F.Fab")
		)
		(fp_line
			(start 0.499872 0.249936)
			(end -0.499872 0.249936)
			(stroke
				(width 0.1)
				(type default)
			)
			(layer "F.Fab")
		)
		(pad "A" smd rect
			(at -0.47498 0)
			(size 0.6096 0.7112)
			(layers "F.Cu" "F.Mask" "F.Paste")
			(net "LED_PWRGD_PVCCFA_EHV_FIVRA_CPU1")
		)
		(pad "C" smd rect
			(at 0.47498 0)
			(size 0.6096 0.7112)
			(layers "F.Cu" "F.Mask" "F.Paste")
			(net "LED_PWRGD_PVCCFA_EHV_FIVRA_CP_2")
		)
	)
	(footprint ""
		(layer "F.Cu")
		(at 40.6146 -104.993948 180)
		(property "Reference" "R4567"
			(at 0 0 180)
			(layer "F.SilkS")
			(hide yes)
			(effects
				(font
					(size 1.27 1.27)
				)
			)
		)
		(property "Value" ""
			(at 0 0 180)
			(layer "F.Fab")
			(effects
				(font
					(size 1.27 1.27)
				)
			)
		)
		(duplicate_pad_numbers_are_jumpers no)
		(fp_line
			(start 0.7874 0.4064)
			(end -0.7874 0.4064)
			(stroke
				(width 0.1524)
				(type default)
			)
			(layer "F.SilkS")
		)
		(fp_line
			(start 0.7874 -0.4064)
			(end 0.7874 0.4064)
			(stroke
				(width 0.1524)
				(type default)
			)
			(layer "F.SilkS")
		)
		(fp_line
			(start -0.7874 0.4064)
			(end -0.7874 -0.4064)
			(stroke
				(width 0.1524)
				(type default)
			)
			(layer "F.SilkS")
		)
		(fp_line
			(start -0.7874 -0.4064)
			(end 0.7874 -0.4064)
			(stroke
				(width 0.1524)
				(type default)
			)
			(layer "F.SilkS")
		)
		(fp_line
			(start 0.67945 0.3048)
			(end 0.120396 0.3048)
			(stroke
				(width 0.1)
				(type default)
			)
			(layer "F.Fab")
		)
		(fp_line
			(start 0.67945 -0.3048)
			(end 0.67945 0.3048)
			(stroke
				(width 0.1)
				(type default)
			)
			(layer "F.Fab")
		)
		(fp_line
			(start 0.12065 -0.2794)
			(end 0.12065 -0.3048)
			(stroke
				(width 0.1)
				(type default)
			)
			(layer "F.Fab")
		)
		(fp_line
			(start 0.12065 -0.3048)
			(end 0.67945 -0.3048)
			(stroke
				(width 0.1)
				(type default)
			)
			(layer "F.Fab")
		)
		(fp_line
			(start 0.120396 0.3048)
			(end 0.120396 0.2794)
			(stroke
				(width 0.1)
				(type default)
			)
			(layer "F.Fab")
		)
		(fp_line
			(start 0.120396 0.2794)
			(end -0.12065 0.2794)
			(stroke
				(width 0.1)
				(type default)
			)
			(layer "F.Fab")
		)
		(fp_line
			(start -0.12065 0.3048)
			(end -0.67945 0.3048)
			(stroke
				(width 0.1)
				(type default)
			)
			(layer "F.Fab")
		)
		(fp_line
			(start -0.12065 0.2794)
			(end -0.12065 0.3048)
			(stroke
				(width 0.1)
				(type default)
			)
			(layer "F.Fab")
		)
		(fp_line
			(start -0.12065 -0.2794)
			(end 0.12065 -0.2794)
			(stroke
				(width 0.1)
				(type default)
			)
			(layer "F.Fab")
		)
		(fp_line
			(start -0.12065 -0.305054)
			(end -0.12065 -0.2794)
			(stroke
				(width 0.1)
				(type default)
			)
			(layer "F.Fab")
		)
		(fp_line
			(start -0.67945 0.3048)
			(end -0.67945 -0.305054)
			(stroke
				(width 0.1)
				(type default)
			)
			(layer "F.Fab")
		)
		(fp_line
			(start -0.67945 -0.305054)
			(end -0.12065 -0.305054)
			(stroke
				(width 0.1)
				(type default)
			)
			(layer "F.Fab")
		)
		(pad "1" smd circle
			(at -0.40005 0 180)
			(size 0 0)
			(layers "F.Cu" "F.Mask" "F.Paste")
			(net "P3V3_PDB_AUX_ADC")
		)
		(pad "2" smd circle
			(at 0.40005 0 180)
			(size 0 0)
			(layers "F.Cu" "F.Mask" "F.Paste")
			(net "P1V581_PDB_ADC")
		)
	)
	(footprint ""
		(layer "F.Cu")
		(at 223.70288 -44.922948)
		(property "Reference" "R3534"
			(at 0 0 0)
			(layer "F.SilkS")
			(hide yes)
			(effects
				(font
					(size 1.27 1.27)
				)
			)
		)
		(property "Value" ""
			(at 0 0 0)
			(layer "F.Fab")
			(effects
				(font
					(size 1.27 1.27)
				)
			)
		)
		(duplicate_pad_numbers_are_jumpers no)
		(fp_line
			(start -0.7874 -0.4064)
			(end 0.7874 -0.4064)
			(stroke
				(width 0.1524)
				(type default)
			)
			(layer "F.SilkS")
		)
		(fp_line
			(start -0.7874 0.4064)
			(end -0.7874 -0.4064)
			(stroke
				(width 0.1524)
				(type default)
			)
			(layer "F.SilkS")
		)
		(fp_line
			(start 0.7874 -0.4064)
			(end 0.7874 0.4064)
			(stroke
				(width 0.1524)
				(type default)
			)
			(layer "F.SilkS")
		)
		(fp_line
			(start 0.7874 0.4064)
			(end -0.7874 0.4064)
			(stroke
				(width 0.1524)
				(type default)
			)
			(layer "F.SilkS")
		)
		(fp_line
			(start -0.67945 -0.305054)
			(end -0.12065 -0.305054)
			(stroke
				(width 0.1)
				(type default)
			)
			(layer "F.Fab")
		)
		(fp_line
			(start -0.67945 0.3048)
			(end -0.67945 -0.305054)
			(stroke
				(width 0.1)
				(type default)
			)
			(layer "F.Fab")
		)
		(fp_line
			(start -0.12065 -0.305054)
			(end -0.12065 -0.2794)
			(stroke
				(width 0.1)
				(type default)
			)
			(layer "F.Fab")
		)
		(fp_line
			(start -0.12065 -0.2794)
			(end 0.12065 -0.2794)
			(stroke
				(width 0.1)
				(type default)
			)
			(layer "F.Fab")
		)
		(fp_line
			(start -0.12065 0.2794)
			(end -0.12065 0.3048)
			(stroke
				(width 0.1)
				(type default)
			)
			(layer "F.Fab")
		)
		(fp_line
			(start -0.12065 0.3048)
			(end -0.67945 0.3048)
			(stroke
				(width 0.1)
				(type default)
			)
			(layer "F.Fab")
		)
		(fp_line
			(start 0.120396 0.2794)
			(end -0.12065 0.2794)
			(stroke
				(width 0.1)
				(type default)
			)
			(layer "F.Fab")
		)
		(fp_line
			(start 0.120396 0.3048)
			(end 0.120396 0.2794)
			(stroke
				(width 0.1)
				(type default)
			)
			(layer "F.Fab")
		)
		(fp_line
			(start 0.12065 -0.3048)
			(end 0.67945 -0.3048)
			(stroke
				(width 0.1)
				(type default)
			)
			(layer "F.Fab")
		)
		(fp_line
			(start 0.12065 -0.2794)
			(end 0.12065 -0.3048)
			(stroke
				(width 0.1)
				(type default)
			)
			(layer "F.Fab")
		)
		(fp_line
			(start 0.67945 -0.3048)
			(end 0.67945 0.3048)
			(stroke
				(width 0.1)
				(type default)
			)
			(layer "F.Fab")
		)
		(fp_line
			(start 0.67945 0.3048)
			(end 0.120396 0.3048)
			(stroke
				(width 0.1)
				(type default)
			)
			(layer "F.Fab")
		)
		(pad "1" smd circle
			(at -0.40005 0)
			(size 0 0)
			(layers "F.Cu" "F.Mask" "F.Paste")
			(net "SMB_E1S_3V3AUX_ISO_SDA_R")
		)
		(pad "2" smd circle
			(at 0.40005 0)
			(size 0 0)
			(layers "F.Cu" "F.Mask" "F.Paste")
			(net "SMB_E1S_3V3AUX_ISO_SDA")
		)
	)
	(footprint ""
		(layer "F.Cu")
		(at 162.34283 -75.767438)
		(property "Reference" "R2208"
			(at 0 0 0)
			(layer "F.SilkS")
			(hide yes)
			(effects
				(font
					(size 1.27 1.27)
				)
			)
		)
		(property "Value" ""
			(at 0 0 0)
			(layer "F.Fab")
			(effects
				(font
					(size 1.27 1.27)
				)
			)
		)
		(duplicate_pad_numbers_are_jumpers no)
		(fp_line
			(start -0.7874 -0.4064)
			(end 0.7874 -0.4064)
			(stroke
				(width 0.1524)
				(type default)
			)
			(layer "F.SilkS")
		)
		(fp_line
			(start -0.7874 0.4064)
			(end -0.7874 -0.4064)
			(stroke
				(width 0.1524)
				(type default)
			)
			(layer "F.SilkS")
		)
		(fp_line
			(start 0.7874 -0.4064)
			(end 0.7874 0.4064)
			(stroke
				(width 0.1524)
				(type default)
			)
			(layer "F.SilkS")
		)
		(fp_line
			(start 0.7874 0.4064)
			(end -0.7874 0.4064)
			(stroke
				(width 0.1524)
				(type default)
			)
			(layer "F.SilkS")
		)
		(fp_line
			(start -0.67945 -0.305054)
			(end -0.12065 -0.305054)
			(stroke
				(width 0.1)
				(type default)
			)
			(layer "F.Fab")
		)
		(fp_line
			(start -0.67945 0.3048)
			(end -0.67945 -0.305054)
			(stroke
				(width 0.1)
				(type default)
			)
			(layer "F.Fab")
		)
		(fp_line
			(start -0.12065 -0.305054)
			(end -0.12065 -0.2794)
			(stroke
				(width 0.1)
				(type default)
			)
			(layer "F.Fab")
		)
		(fp_line
			(start -0.12065 -0.2794)
			(end 0.12065 -0.2794)
			(stroke
				(width 0.1)
				(type default)
			)
			(layer "F.Fab")
		)
		(fp_line
			(start -0.12065 0.2794)
			(end -0.12065 0.3048)
			(stroke
				(width 0.1)
				(type default)
			)
			(layer "F.Fab")
		)
		(fp_line
			(start -0.12065 0.3048)
			(end -0.67945 0.3048)
			(stroke
				(width 0.1)
				(type default)
			)
			(layer "F.Fab")
		)
		(fp_line
			(start 0.120396 0.2794)
			(end -0.12065 0.2794)
			(stroke
				(width 0.1)
				(type default)
			)
			(layer "F.Fab")
		)
		(fp_line
			(start 0.120396 0.3048)
			(end 0.120396 0.2794)
			(stroke
				(width 0.1)
				(type default)
			)
			(layer "F.Fab")
		)
		(fp_line
			(start 0.12065 -0.3048)
			(end 0.67945 -0.3048)
			(stroke
				(width 0.1)
				(type default)
			)
			(layer "F.Fab")
		)
		(fp_line
			(start 0.12065 -0.2794)
			(end 0.12065 -0.3048)
			(stroke
				(width 0.1)
				(type default)
			)
			(layer "F.Fab")
		)
		(fp_line
			(start 0.67945 -0.3048)
			(end 0.67945 0.3048)
			(stroke
				(width 0.1)
				(type default)
			)
			(layer "F.Fab")
		)
		(fp_line
			(start 0.67945 0.3048)
			(end 0.120396 0.3048)
			(stroke
				(width 0.1)
				(type default)
			)
			(layer "F.Fab")
		)
		(pad "1" smd circle
			(at -0.40005 0)
			(size 0 0)
			(layers "F.Cu" "F.Mask" "F.Paste")
			(net "SMB_S3M_CPU0_3V3AUX_SDA_R")
		)
		(pad "2" smd circle
			(at 0.40005 0)
			(size 0 0)
			(layers "F.Cu" "F.Mask" "F.Paste")
			(net "SMB_S3M_CPU0_3V3AUX_SDA")
		)
	)
)
